(kicad_pcb
	(version 20260206)
	(generator "pcbnew")
	(generator_version "10.0")
	(general
		(thickness 1.6)
		(legacy_teardrops no)
	)
	(paper "A4")
	(title_block
		(title "v1-chassis-manager — T6M_CM_d_v01_1031_1645.brd")
		(comment 1 "Open CloudServer (Microsoft) / footprints 106-109 of 2512")
	)
	(layers
		(0 "F.Cu" signal "TOP")
		(4 "In1.Cu" signal "GND1")
		(6 "In2.Cu" signal "IN1")
		(8 "In3.Cu" signal "VCC1")
		(10 "In4.Cu" signal "VCC2")
		(12 "In5.Cu" signal "GND2")
		(14 "In6.Cu" signal "IN2")
		(16 "In7.Cu" signal "IN3")
		(18 "In8.Cu" signal "GND3")
		(2 "B.Cu" signal "BOTTOM")
		(9 "F.Adhes" user "F.Adhesive")
		(11 "B.Adhes" user "B.Adhesive")
		(13 "F.Paste" user "Package Geometry/Pastemask Top")
		(15 "B.Paste" user "Package Geometry/Pastemask Bottom")
		(5 "F.SilkS" user "Ref Des/Silkscreen Top")
		(7 "B.SilkS" user "Ref Des/Silkscreen Bottom")
		(1 "F.Mask" user "Board Geometry/Soldermask Top")
		(3 "B.Mask" user "Board Geometry/Soldermask Bottom")
		(17 "Dwgs.User" user "User.Drawings")
		(19 "Cmts.User" user "User.Comments")
		(21 "Eco1.User" user "User.Eco1")
		(23 "Eco2.User" user "User.Eco2")
		(25 "Edge.Cuts" user "Board Geometry/Outline")
		(27 "Margin" user)
		(31 "F.CrtYd" user "Package Geometry/Place Bound Top")
		(29 "B.CrtYd" user "Package Geometry/Place Bound Bottom")
		(35 "F.Fab" user "Ref Des/Assembly Top")
		(33 "B.Fab" user "Ref Des/Assembly Bottom")
	)
	(footprint ""
		(layer "F.Cu")
		(at 144.51076 -188.126624 90)
		(property "Reference" "C759"
			(at 5.519674 -0.903732 90)
			(unlocked yes)
			(layer "F.SilkS")
			(effects
				(font
					(size 0.7874 0.5842)
					(thickness 0.1524)
				)
				(justify left)
			)
		)
		(property "Value" ""
			(at 0 0 90)
			(layer "F.Fab")
			(effects
				(font
					(size 1.27 1.27)
				)
			)
		)
		(duplicate_pad_numbers_are_jumpers no)
		(fp_line
			(start 0.7874 -0.4064)
			(end 0.7874 0.4064)
			(stroke
				(width 0.1524)
				(type default)
			)
			(layer "F.SilkS")
		)
		(fp_line
			(start -0.7874 -0.4064)
			(end 0.7874 -0.4064)
			(stroke
				(width 0.1524)
				(type default)
			)
			(layer "F.SilkS")
		)
		(fp_line
			(start 0 0.381)
			(end 0 -0.381)
			(stroke
				(width 0.1524)
				(type default)
			)
			(layer "F.SilkS")
		)
		(fp_line
			(start 0.7874 0.4064)
			(end -0.7874 0.4064)
			(stroke
				(width 0.1524)
				(type default)
			)
			(layer "F.SilkS")
		)
		(fp_line
			(start -0.7874 0.4064)
			(end -0.7874 -0.4064)
			(stroke
				(width 0.1524)
				(type default)
			)
			(layer "F.SilkS")
		)
		(fp_poly
			(pts
				(xy -0.5334 0.254) (xy -0.635 0.254) (xy -0.635 0.2286) (xy -0.635 -0.254) (xy -0.5334 -0.254) (xy -0.5334 -0.2794)
				(xy 0.5334 -0.2794) (xy 0.5334 -0.254) (xy 0.635 -0.254) (xy 0.635 0.254) (xy 0.5334 0.254) (xy 0.5334 0.2794)
				(xy -0.508 0.2794) (xy -0.5334 0.2794)
			)
			(stroke
				(width 0)
				(type default)
			)
			(fill no)
			(layer "F.CrtYd")
		)
		(pad "1" smd rect
			(at 0.40005 0 90)
			(size 0.4572 0.508)
			(layers "F.Cu" "F.Mask" "F.Paste")
			(net "UART_T12_NODE3_TXD_R")
		)
		(pad "2" smd rect
			(at -0.40005 0 90)
			(size 0.4572 0.508)
			(layers "F.Cu" "F.Mask" "F.Paste")
			(net "GND")
		)
	)
	(footprint ""
		(layer "F.Cu")
		(at 94.451932 -171.250356)
		(property "Reference" "R758"
			(at 86.67369 74.174096 0)
			(unlocked yes)
			(layer "F.SilkS")
			(effects
				(font
					(size 0.7874 0.5842)
					(thickness 0.1524)
				)
				(justify left)
			)
		)
		(property "Value" ""
			(at 0 0 0)
			(layer "F.Fab")
			(effects
				(font
					(size 1.27 1.27)
				)
			)
		)
		(duplicate_pad_numbers_are_jumpers no)
		(fp_line
			(start -0.7874 -0.4064)
			(end 0.7874 -0.4064)
			(stroke
				(width 0.1524)
				(type default)
			)
			(layer "F.SilkS")
		)
		(fp_line
			(start -0.7874 0.4064)
			(end -0.7874 -0.4064)
			(stroke
				(width 0.1524)
				(type default)
			)
			(layer "F.SilkS")
		)
		(fp_line
			(start 0.7874 -0.4064)
			(end 0.7874 0.4064)
			(stroke
				(width 0.1524)
				(type default)
			)
			(layer "F.SilkS")
		)
		(fp_line
			(start 0.7874 0.4064)
			(end -0.7874 0.4064)
			(stroke
				(width 0.1524)
				(type default)
			)
			(layer "F.SilkS")
		)
		(fp_poly
			(pts
				(xy -0.508 0.2794) (xy -0.508 0.2286) (xy -0.635 0.2286) (xy -0.635 -0.254) (xy -0.5334 -0.254)
				(xy -0.5334 -0.2794) (xy 0.5334 -0.2794) (xy 0.5334 -0.254) (xy 0.635 -0.254) (xy 0.635 0.254) (xy 0.5334 0.254)
				(xy 0.5334 0.2794)
			)
			(stroke
				(width 0)
				(type default)
			)
			(fill no)
			(layer "F.CrtYd")
		)
		(pad "1" smd rect
			(at 0.40005 0)
			(size 0.4572 0.508)
			(layers "F.Cu" "F.Mask" "F.Paste")
			(net "FAN3_TACH_IN")
		)
		(pad "2" smd rect
			(at -0.40005 0)
			(size 0.4572 0.508)
			(layers "F.Cu" "F.Mask" "F.Paste")
			(net "FAN3_TACH")
		)
	)
	(footprint ""
		(layer "F.Cu")
		(at 66.53276 -188.126624 90)
		(property "Reference" "C640"
			(at 4.548886 -0.4445 90)
			(unlocked yes)
			(layer "F.SilkS")
			(effects
				(font
					(size 0.7874 0.5842)
					(thickness 0.1524)
				)
				(justify left)
			)
		)
		(property "Value" ""
			(at 0 0 90)
			(layer "F.Fab")
			(effects
				(font
					(size 1.27 1.27)
				)
			)
		)
		(duplicate_pad_numbers_are_jumpers no)
		(fp_line
			(start 0.7874 -0.4064)
			(end 0.7874 0.4064)
			(stroke
				(width 0.1524)
				(type default)
			)
			(layer "F.SilkS")
		)
		(fp_line
			(start -0.7874 -0.4064)
			(end 0.7874 -0.4064)
			(stroke
				(width 0.1524)
				(type default)
			)
			(layer "F.SilkS")
		)
		(fp_line
			(start 0 0.381)
			(end 0 -0.381)
			(stroke
				(width 0.1524)
				(type default)
			)
			(layer "F.SilkS")
		)
		(fp_line
			(start 0.7874 0.4064)
			(end -0.7874 0.4064)
			(stroke
				(width 0.1524)
				(type default)
			)
			(layer "F.SilkS")
		)
		(fp_line
			(start -0.7874 0.4064)
			(end -0.7874 -0.4064)
			(stroke
				(width 0.1524)
				(type default)
			)
			(layer "F.SilkS")
		)
		(fp_poly
			(pts
				(xy -0.5334 0.254) (xy -0.635 0.254) (xy -0.635 0.2286) (xy -0.635 -0.254) (xy -0.5334 -0.254) (xy -0.5334 -0.2794)
				(xy 0.5334 -0.2794) (xy 0.5334 -0.254) (xy 0.635 -0.254) (xy 0.635 0.254) (xy 0.5334 0.254) (xy 0.5334 0.2794)
				(xy -0.508 0.2794) (xy -0.5334 0.2794)
			)
			(stroke
				(width 0)
				(type default)
			)
			(fill no)
			(layer "F.CrtYd")
		)
		(pad "1" smd rect
			(at 0.40005 0 90)
			(size 0.4572 0.508)
			(layers "F.Cu" "F.Mask" "F.Paste")
			(net "T2_NODE3_EN_R")
		)
		(pad "2" smd rect
			(at -0.40005 0 90)
			(size 0.4572 0.508)
			(layers "F.Cu" "F.Mask" "F.Paste")
			(net "GND")
		)
	)
	(footprint ""
		(layer "F.Cu")
		(at 88.12276 -188.126624 90)
		(property "Reference" "C711"
			(at 4.548886 -1.93802 90)
			(unlocked yes)
			(layer "F.SilkS")
			(effects
				(font
					(size 0.7874 0.5842)
					(thickness 0.1524)
				)
				(justify left)
			)
		)
		(property "Value" ""
			(at 0 0 90)
			(layer "F.Fab")
			(effects
				(font
					(size 1.27 1.27)
				)
			)
		)
		(duplicate_pad_numbers_are_jumpers no)
		(fp_line
			(start 0.7874 -0.4064)
			(end 0.7874 0.4064)
			(stroke
				(width 0.1524)
				(type default)
			)
			(layer "F.SilkS")
		)
		(fp_line
			(start -0.7874 -0.4064)
			(end 0.7874 -0.4064)
			(stroke
				(width 0.1524)
				(type default)
			)
			(layer "F.SilkS")
		)
		(fp_line
			(start 0 0.381)
			(end 0 -0.381)
			(stroke
				(width 0.1524)
				(type default)
			)
			(layer "F.SilkS")
		)
		(fp_line
			(start 0.7874 0.4064)
			(end -0.7874 0.4064)
			(stroke
				(width 0.1524)
				(type default)
			)
			(layer "F.SilkS")
		)
		(fp_line
			(start -0.7874 0.4064)
			(end -0.7874 -0.4064)
			(stroke
				(width 0.1524)
				(type default)
			)
			(layer "F.SilkS")
		)
		(fp_poly
			(pts
				(xy -0.5334 0.254) (xy -0.635 0.254) (xy -0.635 0.2286) (xy -0.635 -0.254) (xy -0.5334 -0.254) (xy -0.5334 -0.2794)
				(xy 0.5334 -0.2794) (xy 0.5334 -0.254) (xy 0.635 -0.254) (xy 0.635 0.254) (xy 0.5334 0.254) (xy 0.5334 0.2794)
				(xy -0.508 0.2794) (xy -0.5334 0.2794)
			)
			(stroke
				(width 0)
				(type default)
			)
			(fill no)
			(layer "F.CrtYd")
		)
		(pad "1" smd rect
			(at 0.40005 0 90)
			(size 0.4572 0.508)
			(layers "F.Cu" "F.Mask" "F.Paste")
			(net "UART_T6_NODE3_TXD_R")
		)
		(pad "2" smd rect
			(at -0.40005 0 90)
			(size 0.4572 0.508)
			(layers "F.Cu" "F.Mask" "F.Paste")
			(net "GND")
		)
	)
)
